(kicad_pcb
	(version 20260206)
	(generator "pcbnew")
	(generator_version "10.0")
	(general
		(thickness 1.6)
		(legacy_teardrops no)
	)
	(paper "A4")
	(title_block
		(title "01162023_DA0F0TEBIF0_F0T_Expander_BD_F_brd_V02_OCP.brd")
		(comment 1 "Grand Teton / footprints 2644-2649 of 9728")
	)
	(layers
		(0 "F.Cu" signal "TOP")
		(4 "In1.Cu" signal "GND")
		(6 "In2.Cu" signal "VCC")
		(8 "In3.Cu" signal "VCC1")
		(10 "In4.Cu" signal "GND1")
		(12 "In5.Cu" signal "IN1")
		(14 "In6.Cu" signal "GND2")
		(16 "In7.Cu" signal "IN2")
		(18 "In8.Cu" signal "GND3")
		(20 "In9.Cu" signal "IN3")
		(22 "In10.Cu" signal "GND4")
		(24 "In11.Cu" signal "IN4")
		(26 "In12.Cu" signal "GND5")
		(28 "In13.Cu" signal "IN5")
		(30 "In14.Cu" signal "GND6")
		(32 "In15.Cu" signal "IN6")
		(34 "In16.Cu" signal "GND7")
		(2 "B.Cu" signal "BOTTOM")
		(9 "F.Adhes" user "F.Adhesive")
		(11 "B.Adhes" user "B.Adhesive")
		(13 "F.Paste" user "Package Geometry/Pastemask Top")
		(15 "B.Paste" user "Package Geometry/Pastemask Bottom")
		(5 "F.SilkS" user "Ref Des/Silkscreen Top")
		(7 "B.SilkS" user "Ref Des/Silkscreen Bottom")
		(1 "F.Mask" user "Board Geometry/Soldermask Top")
		(3 "B.Mask" user "Board Geometry/Soldermask Bottom")
		(17 "Dwgs.User" user "User.Drawings")
		(19 "Cmts.User" user "User.Comments")
		(21 "Eco1.User" user "User.Eco1")
		(23 "Eco2.User" user "User.Eco2")
		(25 "Edge.Cuts" user "Board Geometry/Outline")
		(27 "Margin" user)
		(31 "F.CrtYd" user "Package Geometry/Place Bound Top")
		(29 "B.CrtYd" user "Package Geometry/Place Bound Bottom")
		(35 "F.Fab" user "Ref Des/Assembly Top")
		(33 "B.Fab" user "Ref Des/Assembly Bottom")
	)
	(footprint ""
		(layer "F.Cu")
		(at 215.81872 -175.415956 90)
		(property "Reference" "R5913"
			(at 0 0 90)
			(layer "F.SilkS")
			(hide yes)
			(effects
				(font
					(size 1.27 1.27)
				)
			)
		)
		(property "Value" ""
			(at 0 0 90)
			(layer "F.Fab")
			(effects
				(font
					(size 1.27 1.27)
				)
			)
		)
		(duplicate_pad_numbers_are_jumpers no)
		(fp_line
			(start 0.7874 -0.4064)
			(end 0.7874 0.4064)
			(stroke
				(width 0.1524)
				(type default)
			)
			(layer "F.SilkS")
		)
		(fp_line
			(start -0.7874 -0.4064)
			(end 0.7874 -0.4064)
			(stroke
				(width 0.1524)
				(type default)
			)
			(layer "F.SilkS")
		)
		(fp_line
			(start 0.7874 0.4064)
			(end -0.7874 0.4064)
			(stroke
				(width 0.1524)
				(type default)
			)
			(layer "F.SilkS")
		)
		(fp_line
			(start -0.7874 0.4064)
			(end -0.7874 -0.4064)
			(stroke
				(width 0.1524)
				(type default)
			)
			(layer "F.SilkS")
		)
		(fp_line
			(start -0.12065 -0.305054)
			(end -0.12065 -0.2794)
			(stroke
				(width 0.1)
				(type default)
			)
			(layer "F.Fab")
		)
		(fp_line
			(start -0.67945 -0.305054)
			(end -0.12065 -0.305054)
			(stroke
				(width 0.1)
				(type default)
			)
			(layer "F.Fab")
		)
		(fp_line
			(start 0.67945 -0.3048)
			(end 0.67945 0.3048)
			(stroke
				(width 0.1)
				(type default)
			)
			(layer "F.Fab")
		)
		(fp_line
			(start 0.12065 -0.3048)
			(end 0.67945 -0.3048)
			(stroke
				(width 0.1)
				(type default)
			)
			(layer "F.Fab")
		)
		(fp_line
			(start 0.12065 -0.2794)
			(end 0.12065 -0.3048)
			(stroke
				(width 0.1)
				(type default)
			)
			(layer "F.Fab")
		)
		(fp_line
			(start -0.12065 -0.2794)
			(end 0.12065 -0.2794)
			(stroke
				(width 0.1)
				(type default)
			)
			(layer "F.Fab")
		)
		(fp_line
			(start 0.120396 0.2794)
			(end -0.12065 0.2794)
			(stroke
				(width 0.1)
				(type default)
			)
			(layer "F.Fab")
		)
		(fp_line
			(start -0.12065 0.2794)
			(end -0.12065 0.3048)
			(stroke
				(width 0.1)
				(type default)
			)
			(layer "F.Fab")
		)
		(fp_line
			(start 0.67945 0.3048)
			(end 0.120396 0.3048)
			(stroke
				(width 0.1)
				(type default)
			)
			(layer "F.Fab")
		)
		(fp_line
			(start 0.120396 0.3048)
			(end 0.120396 0.2794)
			(stroke
				(width 0.1)
				(type default)
			)
			(layer "F.Fab")
		)
		(fp_line
			(start -0.12065 0.3048)
			(end -0.67945 0.3048)
			(stroke
				(width 0.1)
				(type default)
			)
			(layer "F.Fab")
		)
		(fp_line
			(start -0.67945 0.3048)
			(end -0.67945 -0.305054)
			(stroke
				(width 0.1)
				(type default)
			)
			(layer "F.Fab")
		)
		(pad "1" smd circle
			(at -0.40005 0 90)
			(size 0 0)
			(layers "F.Cu" "F.Mask" "F.Paste")
			(net "RST_BIC_SELF_HW_RST_R_N")
		)
		(pad "2" smd circle
			(at 0.40005 0 90)
			(size 0 0)
			(layers "F.Cu" "F.Mask" "F.Paste")
			(net "P3V3_AUX")
		)
	)
	(footprint ""
		(layer "F.Cu")
		(at 225.446844 -37.47516)
		(property "Reference" "R6086"
			(at 0 0 0)
			(layer "F.SilkS")
			(hide yes)
			(effects
				(font
					(size 1.27 1.27)
				)
			)
		)
		(property "Value" ""
			(at 0 0 0)
			(layer "F.Fab")
			(effects
				(font
					(size 1.27 1.27)
				)
			)
		)
		(duplicate_pad_numbers_are_jumpers no)
		(fp_line
			(start -0.7874 -0.4064)
			(end 0.7874 -0.4064)
			(stroke
				(width 0.1524)
				(type default)
			)
			(layer "F.SilkS")
		)
		(fp_line
			(start -0.7874 0.4064)
			(end -0.7874 -0.4064)
			(stroke
				(width 0.1524)
				(type default)
			)
			(layer "F.SilkS")
		)
		(fp_line
			(start 0.7874 -0.4064)
			(end 0.7874 0.4064)
			(stroke
				(width 0.1524)
				(type default)
			)
			(layer "F.SilkS")
		)
		(fp_line
			(start 0.7874 0.4064)
			(end -0.7874 0.4064)
			(stroke
				(width 0.1524)
				(type default)
			)
			(layer "F.SilkS")
		)
		(fp_line
			(start -0.67945 -0.305054)
			(end -0.12065 -0.305054)
			(stroke
				(width 0.1)
				(type default)
			)
			(layer "F.Fab")
		)
		(fp_line
			(start -0.67945 0.3048)
			(end -0.67945 -0.305054)
			(stroke
				(width 0.1)
				(type default)
			)
			(layer "F.Fab")
		)
		(fp_line
			(start -0.12065 -0.305054)
			(end -0.12065 -0.2794)
			(stroke
				(width 0.1)
				(type default)
			)
			(layer "F.Fab")
		)
		(fp_line
			(start -0.12065 -0.2794)
			(end 0.12065 -0.2794)
			(stroke
				(width 0.1)
				(type default)
			)
			(layer "F.Fab")
		)
		(fp_line
			(start -0.12065 0.2794)
			(end -0.12065 0.3048)
			(stroke
				(width 0.1)
				(type default)
			)
			(layer "F.Fab")
		)
		(fp_line
			(start -0.12065 0.3048)
			(end -0.67945 0.3048)
			(stroke
				(width 0.1)
				(type default)
			)
			(layer "F.Fab")
		)
		(fp_line
			(start 0.120396 0.2794)
			(end -0.12065 0.2794)
			(stroke
				(width 0.1)
				(type default)
			)
			(layer "F.Fab")
		)
		(fp_line
			(start 0.120396 0.3048)
			(end 0.120396 0.2794)
			(stroke
				(width 0.1)
				(type default)
			)
			(layer "F.Fab")
		)
		(fp_line
			(start 0.12065 -0.3048)
			(end 0.67945 -0.3048)
			(stroke
				(width 0.1)
				(type default)
			)
			(layer "F.Fab")
		)
		(fp_line
			(start 0.12065 -0.2794)
			(end 0.12065 -0.3048)
			(stroke
				(width 0.1)
				(type default)
			)
			(layer "F.Fab")
		)
		(fp_line
			(start 0.67945 -0.3048)
			(end 0.67945 0.3048)
			(stroke
				(width 0.1)
				(type default)
			)
			(layer "F.Fab")
		)
		(fp_line
			(start 0.67945 0.3048)
			(end 0.120396 0.3048)
			(stroke
				(width 0.1)
				(type default)
			)
			(layer "F.Fab")
		)
		(pad "1" smd circle
			(at -0.40005 0)
			(size 0 0)
			(layers "F.Cu" "F.Mask" "F.Paste")
			(net "P3V3_SSD8")
		)
		(pad "2" smd circle
			(at 0.40005 0)
			(size 0 0)
			(layers "F.Cu" "F.Mask" "F.Paste")
			(net "P3V3_SSD8_PG_G1")
		)
	)
	(footprint ""
		(layer "F.Cu")
		(at 380.711456 -290.044632 -90)
		(property "Reference" "R4592"
			(at 0 0 270)
			(layer "F.SilkS")
			(hide yes)
			(effects
				(font
					(size 1.27 1.27)
				)
			)
		)
		(property "Value" ""
			(at 0 0 270)
			(layer "F.Fab")
			(effects
				(font
					(size 1.27 1.27)
				)
			)
		)
		(duplicate_pad_numbers_are_jumpers no)
		(fp_line
			(start -0.7874 0.4064)
			(end -0.7874 -0.4064)
			(stroke
				(width 0.1524)
				(type default)
			)
			(layer "F.SilkS")
		)
		(fp_line
			(start 0.7874 0.4064)
			(end -0.7874 0.4064)
			(stroke
				(width 0.1524)
				(type default)
			)
			(layer "F.SilkS")
		)
		(fp_line
			(start -0.7874 -0.4064)
			(end 0.7874 -0.4064)
			(stroke
				(width 0.1524)
				(type default)
			)
			(layer "F.SilkS")
		)
		(fp_line
			(start 0.7874 -0.4064)
			(end 0.7874 0.4064)
			(stroke
				(width 0.1524)
				(type default)
			)
			(layer "F.SilkS")
		)
		(fp_line
			(start -0.67945 0.3048)
			(end -0.67945 -0.305054)
			(stroke
				(width 0.1)
				(type default)
			)
			(layer "F.Fab")
		)
		(fp_line
			(start -0.12065 0.3048)
			(end -0.67945 0.3048)
			(stroke
				(width 0.1)
				(type default)
			)
			(layer "F.Fab")
		)
		(fp_line
			(start 0.120396 0.3048)
			(end 0.120396 0.2794)
			(stroke
				(width 0.1)
				(type default)
			)
			(layer "F.Fab")
		)
		(fp_line
			(start 0.67945 0.3048)
			(end 0.120396 0.3048)
			(stroke
				(width 0.1)
				(type default)
			)
			(layer "F.Fab")
		)
		(fp_line
			(start -0.12065 0.2794)
			(end -0.12065 0.3048)
			(stroke
				(width 0.1)
				(type default)
			)
			(layer "F.Fab")
		)
		(fp_line
			(start 0.120396 0.2794)
			(end -0.12065 0.2794)
			(stroke
				(width 0.1)
				(type default)
			)
			(layer "F.Fab")
		)
		(fp_line
			(start -0.12065 -0.2794)
			(end 0.12065 -0.2794)
			(stroke
				(width 0.1)
				(type default)
			)
			(layer "F.Fab")
		)
		(fp_line
			(start 0.12065 -0.2794)
			(end 0.12065 -0.3048)
			(stroke
				(width 0.1)
				(type default)
			)
			(layer "F.Fab")
		)
		(fp_line
			(start 0.12065 -0.3048)
			(end 0.67945 -0.3048)
			(stroke
				(width 0.1)
				(type default)
			)
			(layer "F.Fab")
		)
		(fp_line
			(start 0.67945 -0.3048)
			(end 0.67945 0.3048)
			(stroke
				(width 0.1)
				(type default)
			)
			(layer "F.Fab")
		)
		(fp_line
			(start -0.67945 -0.305054)
			(end -0.12065 -0.305054)
			(stroke
				(width 0.1)
				(type default)
			)
			(layer "F.Fab")
		)
		(fp_line
			(start -0.12065 -0.305054)
			(end -0.12065 -0.2794)
			(stroke
				(width 0.1)
				(type default)
			)
			(layer "F.Fab")
		)
		(pad "1" smd circle
			(at -0.40005 0 270)
			(size 0 0)
			(layers "F.Cu" "F.Mask" "F.Paste")
			(net "PCEPLL4_VDDA18_PEX3")
		)
		(pad "2" smd circle
			(at 0.40005 0 270)
			(size 0 0)
			(layers "F.Cu" "F.Mask" "F.Paste")
			(net "PCEPLL4_VDDA18_PEX3_R")
		)
	)
	(footprint ""
		(layer "F.Cu")
		(at 181.55285 -176.966372 180)
		(property "Reference" "C4450"
			(at 0 0 180)
			(layer "F.SilkS")
			(hide yes)
			(effects
				(font
					(size 1.27 1.27)
				)
			)
		)
		(property "Value" ""
			(at 0 0 180)
			(layer "F.Fab")
			(effects
				(font
					(size 1.27 1.27)
				)
			)
		)
		(duplicate_pad_numbers_are_jumpers no)
		(fp_line
			(start 0.7874 0.4064)
			(end -0.7874 0.4064)
			(stroke
				(width 0.1524)
				(type default)
			)
			(layer "F.SilkS")
		)
		(fp_line
			(start 0.7874 -0.4064)
			(end 0.7874 0.4064)
			(stroke
				(width 0.1524)
				(type default)
			)
			(layer "F.SilkS")
		)
		(fp_line
			(start -0.7874 0.4064)
			(end -0.7874 -0.4064)
			(stroke
				(width 0.1524)
				(type default)
			)
			(layer "F.SilkS")
		)
		(fp_line
			(start -0.7874 -0.4064)
			(end 0.7874 -0.4064)
			(stroke
				(width 0.1524)
				(type default)
			)
			(layer "F.SilkS")
		)
		(fp_line
			(start 0.67945 0.3048)
			(end 0.120396 0.3048)
			(stroke
				(width 0.1)
				(type default)
			)
			(layer "F.Fab")
		)
		(fp_line
			(start 0.67945 -0.3048)
			(end 0.67945 0.3048)
			(stroke
				(width 0.1)
				(type default)
			)
			(layer "F.Fab")
		)
		(fp_line
			(start 0.12065 -0.2794)
			(end 0.12065 -0.3048)
			(stroke
				(width 0.1)
				(type default)
			)
			(layer "F.Fab")
		)
		(fp_line
			(start 0.12065 -0.3048)
			(end 0.67945 -0.3048)
			(stroke
				(width 0.1)
				(type default)
			)
			(layer "F.Fab")
		)
		(fp_line
			(start 0.120396 0.3048)
			(end 0.120396 0.2794)
			(stroke
				(width 0.1)
				(type default)
			)
			(layer "F.Fab")
		)
		(fp_line
			(start 0.120396 0.2794)
			(end -0.12065 0.2794)
			(stroke
				(width 0.1)
				(type default)
			)
			(layer "F.Fab")
		)
		(fp_line
			(start -0.12065 0.3048)
			(end -0.67945 0.3048)
			(stroke
				(width 0.1)
				(type default)
			)
			(layer "F.Fab")
		)
		(fp_line
			(start -0.12065 0.2794)
			(end -0.12065 0.3048)
			(stroke
				(width 0.1)
				(type default)
			)
			(layer "F.Fab")
		)
		(fp_line
			(start -0.12065 -0.2794)
			(end 0.12065 -0.2794)
			(stroke
				(width 0.1)
				(type default)
			)
			(layer "F.Fab")
		)
		(fp_line
			(start -0.12065 -0.305054)
			(end -0.12065 -0.2794)
			(stroke
				(width 0.1)
				(type default)
			)
			(layer "F.Fab")
		)
		(fp_line
			(start -0.67945 0.3048)
			(end -0.67945 -0.305054)
			(stroke
				(width 0.1)
				(type default)
			)
			(layer "F.Fab")
		)
		(fp_line
			(start -0.67945 -0.305054)
			(end -0.12065 -0.305054)
			(stroke
				(width 0.1)
				(type default)
			)
			(layer "F.Fab")
		)
		(pad "1" smd circle
			(at -0.40005 0 180)
			(size 0 0)
			(layers "F.Cu" "F.Mask" "F.Paste")
			(net "GND")
		)
		(pad "2" smd circle
			(at 0.40005 0 180)
			(size 0 0)
			(layers "F.Cu" "F.Mask" "F.Paste")
			(net "P3V3_AUX")
		)
	)
	(footprint ""
		(layer "F.Cu")
		(at 215.389968 -72.766682 90)
		(property "Reference" "PR7072"
			(at 0 0 90)
			(layer "F.SilkS")
			(hide yes)
			(effects
				(font
					(size 1.27 1.27)
				)
			)
		)
		(property "Value" ""
			(at 0 0 90)
			(layer "F.Fab")
			(effects
				(font
					(size 1.27 1.27)
				)
			)
		)
		(duplicate_pad_numbers_are_jumpers no)
		(fp_line
			(start 0.7874 -0.4064)
			(end 0.7874 0.4064)
			(stroke
				(width 0.1524)
				(type default)
			)
			(layer "F.SilkS")
		)
		(fp_line
			(start -0.7874 -0.4064)
			(end 0.7874 -0.4064)
			(stroke
				(width 0.1524)
				(type default)
			)
			(layer "F.SilkS")
		)
		(fp_line
			(start 0.7874 0.4064)
			(end -0.7874 0.4064)
			(stroke
				(width 0.1524)
				(type default)
			)
			(layer "F.SilkS")
		)
		(fp_line
			(start -0.7874 0.4064)
			(end -0.7874 -0.4064)
			(stroke
				(width 0.1524)
				(type default)
			)
			(layer "F.SilkS")
		)
		(fp_line
			(start -0.12065 -0.305054)
			(end -0.12065 -0.2794)
			(stroke
				(width 0.1)
				(type default)
			)
			(layer "F.Fab")
		)
		(fp_line
			(start -0.67945 -0.305054)
			(end -0.12065 -0.305054)
			(stroke
				(width 0.1)
				(type default)
			)
			(layer "F.Fab")
		)
		(fp_line
			(start 0.67945 -0.3048)
			(end 0.67945 0.3048)
			(stroke
				(width 0.1)
				(type default)
			)
			(layer "F.Fab")
		)
		(fp_line
			(start 0.12065 -0.3048)
			(end 0.67945 -0.3048)
			(stroke
				(width 0.1)
				(type default)
			)
			(layer "F.Fab")
		)
		(fp_line
			(start 0.12065 -0.2794)
			(end 0.12065 -0.3048)
			(stroke
				(width 0.1)
				(type default)
			)
			(layer "F.Fab")
		)
		(fp_line
			(start -0.12065 -0.2794)
			(end 0.12065 -0.2794)
			(stroke
				(width 0.1)
				(type default)
			)
			(layer "F.Fab")
		)
		(fp_line
			(start 0.120396 0.2794)
			(end -0.12065 0.2794)
			(stroke
				(width 0.1)
				(type default)
			)
			(layer "F.Fab")
		)
		(fp_line
			(start -0.12065 0.2794)
			(end -0.12065 0.3048)
			(stroke
				(width 0.1)
				(type default)
			)
			(layer "F.Fab")
		)
		(fp_line
			(start 0.67945 0.3048)
			(end 0.120396 0.3048)
			(stroke
				(width 0.1)
				(type default)
			)
			(layer "F.Fab")
		)
		(fp_line
			(start 0.120396 0.3048)
			(end 0.120396 0.2794)
			(stroke
				(width 0.1)
				(type default)
			)
			(layer "F.Fab")
		)
		(fp_line
			(start -0.12065 0.3048)
			(end -0.67945 0.3048)
			(stroke
				(width 0.1)
				(type default)
			)
			(layer "F.Fab")
		)
		(fp_line
			(start -0.67945 0.3048)
			(end -0.67945 -0.305054)
			(stroke
				(width 0.1)
				(type default)
			)
			(layer "F.Fab")
		)
		(pad "1" smd circle
			(at -0.40005 0 90)
			(size 0 0)
			(layers "F.Cu" "F.Mask" "F.Paste")
			(net "P12V_SSD7_CO_ILIMIT")
		)
		(pad "2" smd circle
			(at 0.40005 0 90)
			(size 0 0)
			(layers "F.Cu" "F.Mask" "F.Paste")
			(net "GND")
		)
	)
	(footprint ""
		(layer "F.Cu")
		(at 441.387484 -96.811592 90)
		(property "Reference" "R765"
			(at 0 0 90)
			(layer "F.SilkS")
			(hide yes)
			(effects
				(font
					(size 1.27 1.27)
				)
			)
		)
		(property "Value" ""
			(at 0 0 90)
			(layer "F.Fab")
			(effects
				(font
					(size 1.27 1.27)
				)
			)
		)
		(duplicate_pad_numbers_are_jumpers no)
		(fp_line
			(start 0.7874 -0.4064)
			(end 0.7874 0.4064)
			(stroke
				(width 0.1524)
				(type default)
			)
			(layer "F.SilkS")
		)
		(fp_line
			(start -0.7874 -0.4064)
			(end 0.7874 -0.4064)
			(stroke
				(width 0.1524)
				(type default)
			)
			(layer "F.SilkS")
		)
		(fp_line
			(start 0.7874 0.4064)
			(end -0.7874 0.4064)
			(stroke
				(width 0.1524)
				(type default)
			)
			(layer "F.SilkS")
		)
		(fp_line
			(start -0.7874 0.4064)
			(end -0.7874 -0.4064)
			(stroke
				(width 0.1524)
				(type default)
			)
			(layer "F.SilkS")
		)
		(fp_line
			(start -0.12065 -0.305054)
			(end -0.12065 -0.2794)
			(stroke
				(width 0.1)
				(type default)
			)
			(layer "F.Fab")
		)
		(fp_line
			(start -0.67945 -0.305054)
			(end -0.12065 -0.305054)
			(stroke
				(width 0.1)
				(type default)
			)
			(layer "F.Fab")
		)
		(fp_line
			(start 0.67945 -0.3048)
			(end 0.67945 0.3048)
			(stroke
				(width 0.1)
				(type default)
			)
			(layer "F.Fab")
		)
		(fp_line
			(start 0.12065 -0.3048)
			(end 0.67945 -0.3048)
			(stroke
				(width 0.1)
				(type default)
			)
			(layer "F.Fab")
		)
		(fp_line
			(start 0.12065 -0.2794)
			(end 0.12065 -0.3048)
			(stroke
				(width 0.1)
				(type default)
			)
			(layer "F.Fab")
		)
		(fp_line
			(start -0.12065 -0.2794)
			(end 0.12065 -0.2794)
			(stroke
				(width 0.1)
				(type default)
			)
			(layer "F.Fab")
		)
		(fp_line
			(start 0.120396 0.2794)
			(end -0.12065 0.2794)
			(stroke
				(width 0.1)
				(type default)
			)
			(layer "F.Fab")
		)
		(fp_line
			(start -0.12065 0.2794)
			(end -0.12065 0.3048)
			(stroke
				(width 0.1)
				(type default)
			)
			(layer "F.Fab")
		)
		(fp_line
			(start 0.67945 0.3048)
			(end 0.120396 0.3048)
			(stroke
				(width 0.1)
				(type default)
			)
			(layer "F.Fab")
		)
		(fp_line
			(start 0.120396 0.3048)
			(end 0.120396 0.2794)
			(stroke
				(width 0.1)
				(type default)
			)
			(layer "F.Fab")
		)
		(fp_line
			(start -0.12065 0.3048)
			(end -0.67945 0.3048)
			(stroke
				(width 0.1)
				(type default)
			)
			(layer "F.Fab")
		)
		(fp_line
			(start -0.67945 0.3048)
			(end -0.67945 -0.305054)
			(stroke
				(width 0.1)
				(type default)
			)
			(layer "F.Fab")
		)
		(pad "1" smd circle
			(at -0.40005 0 90)
			(size 0 0)
			(layers "F.Cu" "F.Mask" "F.Paste")
			(net "SMB_BIC_I2C6_MUX_NIC_ADC_R_SDA")
		)
		(pad "2" smd circle
			(at 0.40005 0 90)
			(size 0 0)
			(layers "F.Cu" "F.Mask" "F.Paste")
			(net "SMB_NIC7_ADC_SDA")
		)
	)
)
